#ISCELL
  mstr_misc dns *
  *
#ISCELL
  pure_quanta quanta_title_block_c *
  *
#ISCELL
  logical_power universal_gnd *
  page29_i100
#CELL
  pure_quanta q_res *
  page29_i101
#CELL
  pure_quanta q_inductor4p_12 *
  page29_i102
#ISCELL
  standard offpage *
  page29_i103
#ISCELL
  standard offpage *
  page29_i104
#ISCELL
  standard offpage *
  page29_i105
#ISCELL
  standard offpage *
  page29_i106
#CELL
  pure_quanta q_res *
  page29_i109
#CELL
  pure_quanta q_res *
  page29_i111
#CELL
  pure_quanta q_inductor4p_12 *
  page29_i113
#ISCELL
  standard offpage *
  page29_i114
#ISCELL
  standard offpage *
  page29_i115
#ISCELL
  standard offpage *
  page29_i116
#ISCELL
  standard offpage *
  page29_i119
#CELL
  pure_quanta q_res *
  page29_i122
#CELL
  pure_quanta q_inductor4p_12 *
  page29_i123
#CELL
  pure_quanta q_res *
  page29_i124
#ISCELL
  standard offpage *
  page29_i125
#ISCELL
  standard offpage *
  page29_i126
#ISCELL
  standard offpage *
  page29_i127
#ISCELL
  standard offpage *
  page29_i128
#ISCELL
  standard offpage *
  page29_i133
#ISCELL
  standard offpage *
  page29_i134
#CELL
  pure_quanta q_res *
  page29_i135
#CELL
  pure_quanta q_res *
  page29_i136
#ISCELL
  standard offpage *
  page29_i137
#ISCELL
  standard offpage *
  page29_i138
#CELL
  pure_quanta q_res *
  page29_i141
#CELL
  pure_quanta q_cap *
  page29_i142
#CELL
  pure_quanta q_cap *
  page29_i143
#CELL
  pure_quanta q_res *
  page29_i144
#ISCELL
  logical_power vccaux15 *
  page29_i145
#CELL
  pure_quanta q_cap *
  page29_i146
#ISCELL
  logical_power universal_gnd *
  page29_i147
#CELL
  pure_quanta q_cap *
  page29_i148
#ISCELL
  logical_power vccaux15 *
  page29_i149
#CELL
  pure_quanta q_cap *
  page29_i150
#ISCELL
  logical_power universal_gnd *
  page29_i151
#CELL
  pure_quanta q_res *
  page29_i153
#ISCELL
  standard offpage *
  page29_i154
#CELL
  pure_quanta q_res *
  page29_i155
#ISCELL
  logical_power universal_gnd *
  page29_i156
#CELL
  pure_quanta q_res *
  page29_i157
#ISCELL
  standard offpage *
  page29_i158
#ISCELL
  logical_power vccaux15 *
  page29_i159
#ISCELL
  standard offpage *
  page29_i160
#CELL
  pure_quanta q_cap *
  page29_i161
#ISCELL
  logical_power vccaux15 *
  page29_i162
#ISCELL
  logical_power universal_gnd *
  page29_i163
#CELL
  pure_quanta 74hc1g126gw *
  page29_i164
#ISCELL
  logical_power vccaux15 *
  page29_i165
#CELL
  pure_quanta q_res *
  page29_i166
#ISCELL
  logical_power universal_gnd *
  page29_i167
#ISCELL
  standard offpage *
  page29_i168
#ISCELL
  standard offpage *
  page29_i169
#CELL
  pure_quanta q_res *
  page29_i170
#ISCELL
  logical_power universal_gnd *
  page29_i171
#CELL
  pure_quanta q_cap *
  page29_i172
#ISCELL
  logical_power universal_gnd *
  page29_i173
#CELL
  pure_quanta 74hc1g126gw *
  page29_i174
#ISCELL
  logical_power universal_gnd *
  page29_i175
#ISCELL
  standard offpage *
  page29_i176
#ISCELL
  logical_power vccaux15 *
  page29_i177
#ISCELL
  standard offpage *
  page29_i178
#ISCELL
  logical_power universal_power *
  page29_i179
#ISCELL
  standard offpage *
  page29_i181
#ISCELL
  logical_power universal_gnd *
  page29_i182
#ISCELL
  logical_power universal_gnd *
  page29_i183
#CELL
  pure_quanta q_res *
  page29_i184
#ISCELL
  logical_power universal_gnd *
  page29_i185
#ISCELL
  standard offpage *
  page29_i186
#ISCELL
  standard offpage *
  page29_i187
#ISCELL
  standard offpage *
  page29_i188
#ISCELL
  standard offpage *
  page29_i189
#ISCELL
  standard offpage *
  page29_i190
#ISCELL
  standard offpage *
  page29_i192
#CELL
  pure_quanta q_cap *
  page29_i193
#CELL
  pure_quanta q_cap *
  page29_i194
#ISCELL
  logical_power universal_gnd *
  page29_i195
#ISCELL
  logical_power universal_power *
  page29_i197
#ISCELL
  standard offpage *
  page29_i199
#ISCELL
  logical_power universal_gnd *
  page29_i200
#CELL
  pure_quanta q_res *
  page29_i201
#CELL
  pure_quanta 2n7002a7 *
  page29_i202
#ISCELL
  logical_power vccaux15 *
  page29_i203
#CELL
  pure_quanta q_res *
  page29_i204
#ISCELL
  standard offpage *
  page29_i205
#CELL
  pure_quanta pi3pcie3212zbex *
  page29_i206
#ISCELL
  standard offpage *
  page29_i207
#ISCELL
  standard offpage *
  page29_i208
#ISCELL
  standard offpage *
  page29_i209
#ISCELL
  standard offpage *
  page29_i210
#CELL
  pure_quanta dt1240e04lp7 *
  page29_i211
#ISCELL
  logical_power universal_gnd *
  page29_i212
#ISCELL
  standard offpage *
  page29_i217
#ISCELL
  standard offpage *
  page29_i218
#CELL
  pure_quanta q_cap *
  page29_i219
#CELL
  pure_quanta q_cap *
  page29_i220
#CELL
  pure_quanta conn9_gsb3111315hr *
  page29_i221
#CELL
  pure_quanta q_res *
  page29_i222
#ISCELL
  logical_power universal_power *
  page29_i95
#CELL
  pure_quanta q_res *
  page29_i96
#ISCELL
  standard offpage *
  page29_i97
#ISCELL
  standard offpage *
  page29_i98
#CELL
  pure_quanta prtr5v0u2x *
  page29_i99
